(kicad_pcb
	(version 20260206)
	(generator "pcbnew")
	(generator_version "10.0")
	(general
		(thickness 1.6)
		(legacy_teardrops no)
	)
	(paper "A4")
	(title_block
		(title "04192023_DAF0TMB3IC0_F0TG_MB_C_brd_V02_OCP.brd")
		(comment 1 "Grand Teton / footprints 989-992 of 8354")
	)
	(layers
		(0 "F.Cu" signal "TOP")
		(4 "In1.Cu" signal "GND")
		(6 "In2.Cu" signal "IN1")
		(8 "In3.Cu" signal "GND1")
		(10 "In4.Cu" signal "IN2")
		(12 "In5.Cu" signal "GND2")
		(14 "In6.Cu" signal "IN3")
		(16 "In7.Cu" signal "GND3")
		(18 "In8.Cu" signal "VCC")
		(20 "In9.Cu" signal "VCC1")
		(22 "In10.Cu" signal "GND4")
		(24 "In11.Cu" signal "IN4")
		(26 "In12.Cu" signal "GND5")
		(28 "In13.Cu" signal "IN5")
		(30 "In14.Cu" signal "GND6")
		(32 "In15.Cu" signal "IN6")
		(34 "In16.Cu" signal "GND7")
		(2 "B.Cu" signal "BOTTOM")
		(9 "F.Adhes" user "F.Adhesive")
		(11 "B.Adhes" user "B.Adhesive")
		(13 "F.Paste" user "Package Geometry/Pastemask Top")
		(15 "B.Paste" user "Package Geometry/Pastemask Bottom")
		(5 "F.SilkS" user "Ref Des/Silkscreen Top")
		(7 "B.SilkS" user "Ref Des/Silkscreen Bottom")
		(1 "F.Mask" user "Board Geometry/Soldermask Top")
		(3 "B.Mask" user "Board Geometry/Soldermask Bottom")
		(17 "Dwgs.User" user "User.Drawings")
		(19 "Cmts.User" user "User.Comments")
		(21 "Eco1.User" user "User.Eco1")
		(23 "Eco2.User" user "User.Eco2")
		(25 "Edge.Cuts" user "Board Geometry/Outline")
		(27 "Margin" user)
		(31 "F.CrtYd" user "Package Geometry/Place Bound Top")
		(29 "B.CrtYd" user "Package Geometry/Place Bound Bottom")
		(35 "F.Fab" user "Ref Des/Assembly Top")
		(33 "B.Fab" user "Ref Des/Assembly Bottom")
	)
	(footprint ""
		(layer "F.Cu")
		(at 442.353192 -28.175458 -90)
		(property "Reference" "PU204"
			(at -6.397498 0.707136 0)
			(unlocked yes)
			(layer "F.SilkS")
			(effects
				(font
					(size 0.7874 0.5842)
					(thickness 0.1524)
				)
				(justify left)
			)
		)
		(property "Value" ""
			(at 0 0 270)
			(layer "F.Fab")
			(effects
				(font
					(size 1.27 1.27)
				)
			)
		)
		(duplicate_pad_numbers_are_jumpers no)
		(fp_line
			(start -1.549908 2.549906)
			(end -0.753872 2.549906)
			(stroke
				(width 0.1524)
				(type default)
			)
			(layer "F.SilkS")
		)
		(fp_line
			(start -0.245872 2.549906)
			(end 0.245872 2.549906)
			(stroke
				(width 0.1524)
				(type default)
			)
			(layer "F.SilkS")
		)
		(fp_line
			(start 0.753872 2.549906)
			(end 1.549908 2.549906)
			(stroke
				(width 0.1524)
				(type default)
			)
			(layer "F.SilkS")
		)
		(fp_line
			(start 1.549908 2.549906)
			(end 1.549908 2.253996)
			(stroke
				(width 0.1524)
				(type default)
			)
			(layer "F.SilkS")
		)
		(fp_line
			(start -1.549908 2.253996)
			(end -1.549908 2.549906)
			(stroke
				(width 0.1524)
				(type default)
			)
			(layer "F.SilkS")
		)
		(fp_line
			(start 1.549908 -2.253996)
			(end 1.549908 -2.549906)
			(stroke
				(width 0.1524)
				(type default)
			)
			(layer "F.SilkS")
		)
		(fp_line
			(start -1.549908 -2.549906)
			(end -1.549908 -2.251964)
			(stroke
				(width 0.1524)
				(type default)
			)
			(layer "F.SilkS")
		)
		(fp_line
			(start -0.752094 -2.549906)
			(end -1.549908 -2.549906)
			(stroke
				(width 0.1524)
				(type default)
			)
			(layer "F.SilkS")
		)
		(fp_line
			(start 0.2413 -2.549906)
			(end -0.2413 -2.549906)
			(stroke
				(width 0.1524)
				(type default)
			)
			(layer "F.SilkS")
		)
		(fp_line
			(start 1.549908 -2.549906)
			(end 0.752094 -2.549906)
			(stroke
				(width 0.1524)
				(type default)
			)
			(layer "F.SilkS")
		)
		(fp_poly
			(pts
				(xy -2.461768 -3.528568) (xy -1.981708 -2.70637) (xy -2.927604 -2.816098)
			)
			(stroke
				(width 0)
				(type default)
			)
			(fill yes)
			(layer "F.SilkS")
		)
		(fp_line
			(start -1.549908 2.549906)
			(end 1.549908 2.549906)
			(stroke
				(width 0.1)
				(type default)
			)
			(layer "F.Fab")
		)
		(fp_line
			(start 1.549908 2.549906)
			(end 1.549908 -2.549906)
			(stroke
				(width 0.1)
				(type default)
			)
			(layer "F.Fab")
		)
		(fp_line
			(start -1.549908 -2.549906)
			(end -1.549908 2.549906)
			(stroke
				(width 0.1)
				(type default)
			)
			(layer "F.Fab")
		)
		(fp_line
			(start 1.549908 -2.549906)
			(end -1.549908 -2.549906)
			(stroke
				(width 0.1)
				(type default)
			)
			(layer "F.Fab")
		)
		(fp_poly
			(pts
				(xy -1.891538 -1.999996) (xy -2.7432 -1.574292) (xy -2.7432 -2.4257)
			)
			(stroke
				(width 0)
				(type default)
			)
			(fill yes)
			(layer "F.Fab")
		)
		(fp_text user "11"
			(at 1.00076 7.279132 270)
			(unlocked yes)
			(layer "F.SilkS")
			(effects
				(font
					(size 0.635 0.4064)
					(thickness 0.1524)
				)
			)
		)
		(fp_text user "12"
			(at 3.553968 5.04698 180)
			(unlocked yes)
			(layer "F.SilkS")
			(effects
				(font
					(size 0.635 0.4064)
					(thickness 0.1524)
				)
			)
		)
		(fp_text user "10"
			(at -2.50952 4.215892 270)
			(unlocked yes)
			(layer "F.SilkS")
			(effects
				(font
					(size 0.635 0.4064)
					(thickness 0.1524)
				)
			)
		)
		(fp_text user "9"
			(at -2.338832 2.5908 180)
			(unlocked yes)
			(layer "F.SilkS")
			(effects
				(font
					(size 0.635 0.4064)
					(thickness 0.1524)
				)
			)
		)
		(fp_text user "21_22"
			(at -0.0762 -3.401568 270)
			(unlocked yes)
			(layer "F.SilkS")
			(effects
				(font
					(size 0.635 0.4064)
					(thickness 0.1524)
				)
			)
		)
		(fp_text user "20"
			(at 1.905508 -3.51536 180)
			(unlocked yes)
			(layer "F.SilkS")
			(effects
				(font
					(size 0.635 0.4064)
					(thickness 0.1524)
				)
			)
		)
		(fp_text user "11"
			(at 1.1938 3.329432 270)
			(unlocked yes)
			(layer "F.Fab")
			(effects
				(font
					(size 0.635 0.4064)
					(thickness 0.1524)
				)
			)
		)
		(fp_text user "10"
			(at -1.4224 3.253232 270)
			(unlocked yes)
			(layer "F.Fab")
			(effects
				(font
					(size 0.635 0.4064)
					(thickness 0.1524)
				)
			)
		)
		(fp_text user "12"
			(at 2.207768 2.7178 180)
			(unlocked yes)
			(layer "F.Fab")
			(effects
				(font
					(size 0.635 0.4064)
					(thickness 0.1524)
				)
			)
		)
		(fp_text user "9"
			(at -2.338832 2.5908 180)
			(unlocked yes)
			(layer "F.Fab")
			(effects
				(font
					(size 0.635 0.4064)
					(thickness 0.1524)
				)
			)
		)
		(fp_text user "20"
			(at 2.055368 -2.7686 180)
			(unlocked yes)
			(layer "F.Fab")
			(effects
				(font
					(size 0.635 0.4064)
					(thickness 0.1524)
				)
			)
		)
		(fp_text user "21_22"
			(at -0.0762 -3.401568 270)
			(unlocked yes)
			(layer "F.Fab")
			(effects
				(font
					(size 0.635 0.4064)
					(thickness 0.1524)
				)
			)
		)
		(pad "1" smd circle
			(at -1.374902 -1.999996 180)
			(size 0 0)
			(layers "F.Cu" "F.Mask" "F.Paste")
			(net "P12V_OCP_EN_1_R2")
		)
		(pad "2" smd rect
			(at -1.400048 -1.500124 180)
			(size 0.254 0.8128)
			(layers "F.Cu" "F.Mask" "F.Paste")
			(net "GND")
		)
		(pad "3" smd rect
			(at -1.400048 -0.999998 180)
			(size 0.254 0.8128)
			(layers "F.Cu" "F.Mask" "F.Paste")
			(net "GND")
		)
		(pad "4" smd rect
			(at -1.400048 -0.499872 180)
			(size 0.254 0.8128)
			(layers "F.Cu" "F.Mask" "F.Paste")
			(net "P12V_OCP_TIMER_1")
		)
		(pad "5" smd rect
			(at -1.400048 0 180)
			(size 0.254 0.8128)
			(layers "F.Cu" "F.Mask" "F.Paste")
			(net "P12V_OCP_ISET_1")
		)
		(pad "6" smd rect
			(at -1.400048 0.499872 180)
			(size 0.254 0.8128)
			(layers "F.Cu" "F.Mask" "F.Paste")
			(net "P12V_OCP_SS_1")
		)
		(pad "7" smd rect
			(at -1.400048 0.999998 180)
			(size 0.254 0.8128)
			(layers "F.Cu" "F.Mask" "F.Paste")
			(net "GND")
		)
		(pad "8" smd rect
			(at -1.400048 1.500124 180)
			(size 0.254 0.8128)
			(layers "F.Cu" "F.Mask" "F.Paste")
			(net "P12V_OCP_IMON_1")
		)
		(pad "9" smd rect
			(at -1.400048 1.999996 180)
			(size 0.254 0.8128)
			(layers "F.Cu" "F.Mask" "F.Paste")
			(net "P12V_OCP_FLTB_1")
		)
		(pad "10" smd rect
			(at -0.499872 2.400046 270)
			(size 0.254 0.8128)
			(layers "F.Cu" "F.Mask" "F.Paste")
			(net "HP_LVC3_OCP_V3_1_P12V_PWRGD")
		)
		(pad "11" smd rect
			(at 0.499872 2.400046 270)
			(size 0.254 0.8128)
			(layers "F.Cu" "F.Mask" "F.Paste")
			(net "P12V_OCP_OV_FB_1")
		)
		(pad "12" smd rect
			(at 1.400048 1.999996 180)
			(size 0.254 0.8128)
			(layers "F.Cu" "F.Mask" "F.Paste")
			(net "P12V_OCP_AVIN_PD_1")
		)
		(pad "13" smd rect
			(at 1.400048 1.500124 180)
			(size 0.254 0.8128)
			(layers "F.Cu" "F.Mask" "F.Paste")
			(net "P12V_OCP_SFF")
		)
		(pad "14" smd rect
			(at 1.400048 0.999998 180)
			(size 0.254 0.8128)
			(layers "F.Cu" "F.Mask" "F.Paste")
			(net "P12V_OCP_SFF")
		)
		(pad "15" smd rect
			(at 1.400048 0.499872 180)
			(size 0.254 0.8128)
			(layers "F.Cu" "F.Mask" "F.Paste")
			(net "P12V_OCP_SFF")
		)
		(pad "16" smd rect
			(at 1.400048 0 180)
			(size 0.254 0.8128)
			(layers "F.Cu" "F.Mask" "F.Paste")
			(net "P12V_OCP_SFF")
		)
		(pad "17" smd rect
			(at 1.400048 -0.499872 180)
			(size 0.254 0.8128)
			(layers "F.Cu" "F.Mask" "F.Paste")
			(net "P12V_OCP_SFF")
		)
		(pad "18" smd rect
			(at 1.400048 -0.999998 180)
			(size 0.254 0.8128)
			(layers "F.Cu" "F.Mask" "F.Paste")
			(net "P12V_OCP_SFF")
		)
		(pad "19" smd rect
			(at 1.400048 -1.500124 180)
			(size 0.254 0.8128)
			(layers "F.Cu" "F.Mask" "F.Paste")
			(net "P12V_OCP_SFF")
		)
		(pad "20" smd rect
			(at 1.400048 -1.999996 180)
			(size 0.254 0.8128)
			(layers "F.Cu" "F.Mask" "F.Paste")
			(net "P12V_OCP_SFF")
		)
		(pad "21_22" smd circle
			(at 0.499872 -2.337562 180)
			(size 0 0)
			(layers "F.Cu" "F.Mask" "F.Paste")
			(net "P12V_AUX")
		)
		(pad "23" smd rect
			(at 0 -1.100074 180)
			(size 0.254 1.27)
			(layers "F.Cu" "F.Mask" "F.Paste")
			(net "P12V_AUX")
		)
		(pad "24" smd rect
			(at 0 -0.199898 180)
			(size 0.254 1.27)
			(layers "F.Cu" "F.Mask" "F.Paste")
			(net "P12V_AUX")
		)
		(pad "25" smd rect
			(at 0 0.700024 180)
			(size 0.254 1.27)
			(layers "F.Cu" "F.Mask" "F.Paste")
			(net "P12V_AUX")
		)
		(pad "26" smd rect
			(at 0 1.599946 180)
			(size 0.254 1.27)
			(layers "F.Cu" "F.Mask" "F.Paste")
			(net "P12V_AUX")
		)
	)
	(footprint ""
		(layer "F.Cu")
		(at 81.537302 -375.49963 -90)
		(property "Reference" "C732"
			(at 0 0 270)
			(layer "F.SilkS")
			(hide yes)
			(effects
				(font
					(size 1.27 1.27)
				)
			)
		)
		(property "Value" ""
			(at 0 0 270)
			(layer "F.Fab")
			(effects
				(font
					(size 1.27 1.27)
				)
			)
		)
		(duplicate_pad_numbers_are_jumpers no)
		(fp_line
			(start -0.299974 0.150114)
			(end -0.299974 -0.150114)
			(stroke
				(width 0.1)
				(type default)
			)
			(layer "F.Fab")
		)
		(fp_line
			(start 0.299974 0.150114)
			(end -0.299974 0.150114)
			(stroke
				(width 0.1)
				(type default)
			)
			(layer "F.Fab")
		)
		(fp_line
			(start -0.299974 -0.150114)
			(end 0.299974 -0.150114)
			(stroke
				(width 0.1)
				(type default)
			)
			(layer "F.Fab")
		)
		(fp_line
			(start 0.299974 -0.150114)
			(end 0.299974 0.150114)
			(stroke
				(width 0.1)
				(type default)
			)
			(layer "F.Fab")
		)
		(pad "1" smd rect
			(at -0.2667 0 270)
			(size 0.3048 0.381)
			(layers "F.Cu" "F.Mask" "F.Paste")
			(net "P5E_CPU1_P1_TX_C_DN<4>")
		)
		(pad "2" smd rect
			(at 0.2667 0 270)
			(size 0.3048 0.381)
			(layers "F.Cu" "F.Mask" "F.Paste")
			(net "P5E_CPU1_P1_TX_DN<4>")
		)
	)
	(footprint ""
		(layer "F.Cu")
		(at 335.818226 -339.625432 90)
		(property "Reference" "PR82"
			(at 0 0 90)
			(layer "F.SilkS")
			(hide yes)
			(effects
				(font
					(size 1.27 1.27)
				)
			)
		)
		(property "Value" ""
			(at 0 0 90)
			(layer "F.Fab")
			(effects
				(font
					(size 1.27 1.27)
				)
			)
		)
		(duplicate_pad_numbers_are_jumpers no)
		(fp_line
			(start 0.7874 -0.4064)
			(end 0.7874 0.4064)
			(stroke
				(width 0.1524)
				(type default)
			)
			(layer "F.SilkS")
		)
		(fp_line
			(start -0.7874 -0.4064)
			(end 0.7874 -0.4064)
			(stroke
				(width 0.1524)
				(type default)
			)
			(layer "F.SilkS")
		)
		(fp_line
			(start 0.7874 0.4064)
			(end -0.7874 0.4064)
			(stroke
				(width 0.1524)
				(type default)
			)
			(layer "F.SilkS")
		)
		(fp_line
			(start -0.7874 0.4064)
			(end -0.7874 -0.4064)
			(stroke
				(width 0.1524)
				(type default)
			)
			(layer "F.SilkS")
		)
		(fp_line
			(start -0.12065 -0.305054)
			(end -0.12065 -0.2794)
			(stroke
				(width 0.1)
				(type default)
			)
			(layer "F.Fab")
		)
		(fp_line
			(start -0.67945 -0.305054)
			(end -0.12065 -0.305054)
			(stroke
				(width 0.1)
				(type default)
			)
			(layer "F.Fab")
		)
		(fp_line
			(start 0.67945 -0.3048)
			(end 0.67945 0.3048)
			(stroke
				(width 0.1)
				(type default)
			)
			(layer "F.Fab")
		)
		(fp_line
			(start 0.12065 -0.3048)
			(end 0.67945 -0.3048)
			(stroke
				(width 0.1)
				(type default)
			)
			(layer "F.Fab")
		)
		(fp_line
			(start 0.12065 -0.2794)
			(end 0.12065 -0.3048)
			(stroke
				(width 0.1)
				(type default)
			)
			(layer "F.Fab")
		)
		(fp_line
			(start -0.12065 -0.2794)
			(end 0.12065 -0.2794)
			(stroke
				(width 0.1)
				(type default)
			)
			(layer "F.Fab")
		)
		(fp_line
			(start 0.120396 0.2794)
			(end -0.12065 0.2794)
			(stroke
				(width 0.1)
				(type default)
			)
			(layer "F.Fab")
		)
		(fp_line
			(start -0.12065 0.2794)
			(end -0.12065 0.3048)
			(stroke
				(width 0.1)
				(type default)
			)
			(layer "F.Fab")
		)
		(fp_line
			(start 0.67945 0.3048)
			(end 0.120396 0.3048)
			(stroke
				(width 0.1)
				(type default)
			)
			(layer "F.Fab")
		)
		(fp_line
			(start 0.120396 0.3048)
			(end 0.120396 0.2794)
			(stroke
				(width 0.1)
				(type default)
			)
			(layer "F.Fab")
		)
		(fp_line
			(start -0.12065 0.3048)
			(end -0.67945 0.3048)
			(stroke
				(width 0.1)
				(type default)
			)
			(layer "F.Fab")
		)
		(fp_line
			(start -0.67945 0.3048)
			(end -0.67945 -0.305054)
			(stroke
				(width 0.1)
				(type default)
			)
			(layer "F.Fab")
		)
		(pad "1" smd circle
			(at -0.40005 0 90)
			(size 0 0)
			(layers "F.Cu" "F.Mask" "F.Paste")
			(net "SW_PVDDCR_CPU1_P0_BOOT1")
		)
		(pad "2" smd circle
			(at 0.40005 0 90)
			(size 0 0)
			(layers "F.Cu" "F.Mask" "F.Paste")
			(net "SW_PVDDCR_CPU1_P0_BOOT1_R")
		)
	)
	(footprint ""
		(layer "F.Cu")
		(at 293.038022 -52.02809)
		(property "Reference" "R422"
			(at 0 0 0)
			(layer "F.SilkS")
			(hide yes)
			(effects
				(font
					(size 1.27 1.27)
				)
			)
		)
		(property "Value" ""
			(at 0 0 0)
			(layer "F.Fab")
			(effects
				(font
					(size 1.27 1.27)
				)
			)
		)
		(duplicate_pad_numbers_are_jumpers no)
		(fp_line
			(start -0.7874 -0.4064)
			(end 0.7874 -0.4064)
			(stroke
				(width 0.1524)
				(type default)
			)
			(layer "F.SilkS")
		)
		(fp_line
			(start -0.7874 0.4064)
			(end -0.7874 -0.4064)
			(stroke
				(width 0.1524)
				(type default)
			)
			(layer "F.SilkS")
		)
		(fp_line
			(start 0.7874 -0.4064)
			(end 0.7874 0.4064)
			(stroke
				(width 0.1524)
				(type default)
			)
			(layer "F.SilkS")
		)
		(fp_line
			(start 0.7874 0.4064)
			(end -0.7874 0.4064)
			(stroke
				(width 0.1524)
				(type default)
			)
			(layer "F.SilkS")
		)
		(fp_line
			(start -0.67945 -0.305054)
			(end -0.12065 -0.305054)
			(stroke
				(width 0.1)
				(type default)
			)
			(layer "F.Fab")
		)
		(fp_line
			(start -0.67945 0.3048)
			(end -0.67945 -0.305054)
			(stroke
				(width 0.1)
				(type default)
			)
			(layer "F.Fab")
		)
		(fp_line
			(start -0.12065 -0.305054)
			(end -0.12065 -0.2794)
			(stroke
				(width 0.1)
				(type default)
			)
			(layer "F.Fab")
		)
		(fp_line
			(start -0.12065 -0.2794)
			(end 0.12065 -0.2794)
			(stroke
				(width 0.1)
				(type default)
			)
			(layer "F.Fab")
		)
		(fp_line
			(start -0.12065 0.2794)
			(end -0.12065 0.3048)
			(stroke
				(width 0.1)
				(type default)
			)
			(layer "F.Fab")
		)
		(fp_line
			(start -0.12065 0.3048)
			(end -0.67945 0.3048)
			(stroke
				(width 0.1)
				(type default)
			)
			(layer "F.Fab")
		)
		(fp_line
			(start 0.120396 0.2794)
			(end -0.12065 0.2794)
			(stroke
				(width 0.1)
				(type default)
			)
			(layer "F.Fab")
		)
		(fp_line
			(start 0.120396 0.3048)
			(end 0.120396 0.2794)
			(stroke
				(width 0.1)
				(type default)
			)
			(layer "F.Fab")
		)
		(fp_line
			(start 0.12065 -0.3048)
			(end 0.67945 -0.3048)
			(stroke
				(width 0.1)
				(type default)
			)
			(layer "F.Fab")
		)
		(fp_line
			(start 0.12065 -0.2794)
			(end 0.12065 -0.3048)
			(stroke
				(width 0.1)
				(type default)
			)
			(layer "F.Fab")
		)
		(fp_line
			(start 0.67945 -0.3048)
			(end 0.67945 0.3048)
			(stroke
				(width 0.1)
				(type default)
			)
			(layer "F.Fab")
		)
		(fp_line
			(start 0.67945 0.3048)
			(end 0.120396 0.3048)
			(stroke
				(width 0.1)
				(type default)
			)
			(layer "F.Fab")
		)
		(pad "1" smd circle
			(at -0.40005 0)
			(size 0 0)
			(layers "F.Cu" "F.Mask" "F.Paste")
			(net "PVDD18_S5_P0")
		)
		(pad "2" smd circle
			(at 0.40005 0)
			(size 0 0)
			(layers "F.Cu" "F.Mask" "F.Paste")
			(net "RST_CPU0_SYS_N")
		)
	)
)
